(kicad_pcb
	(version 20260206)
	(generator "pcbnew")
	(generator_version "10.0")
	(general
		(thickness 1.6)
		(legacy_teardrops no)
	)
	(paper "A4")
	(title_block
		(title "03242023_DA0F0TMBIJ0_F0T_Motherboard_J_brd_V01_OCP.brd")
		(comment 1 "Grand Teton / footprints 3484-3488 of 6105")
	)
	(layers
		(0 "F.Cu" signal "TOP")
		(4 "In1.Cu" signal "GND")
		(6 "In2.Cu" signal "IN1")
		(8 "In3.Cu" signal "GND1")
		(10 "In4.Cu" signal "IN2")
		(12 "In5.Cu" signal "GND2")
		(14 "In6.Cu" signal "IN3")
		(16 "In7.Cu" signal "GND3")
		(18 "In8.Cu" signal "VCC")
		(20 "In9.Cu" signal "VCC1")
		(22 "In10.Cu" signal "GND4")
		(24 "In11.Cu" signal "IN4")
		(26 "In12.Cu" signal "GND5")
		(28 "In13.Cu" signal "IN5")
		(30 "In14.Cu" signal "GND6")
		(32 "In15.Cu" signal "IN6")
		(34 "In16.Cu" signal "GND7")
		(2 "B.Cu" signal "BOTTOM")
		(9 "F.Adhes" user "F.Adhesive")
		(11 "B.Adhes" user "B.Adhesive")
		(13 "F.Paste" user "Package Geometry/Pastemask Top")
		(15 "B.Paste" user "Package Geometry/Pastemask Bottom")
		(5 "F.SilkS" user "Ref Des/Silkscreen Top")
		(7 "B.SilkS" user "Ref Des/Silkscreen Bottom")
		(1 "F.Mask" user "Board Geometry/Soldermask Top")
		(3 "B.Mask" user "Board Geometry/Soldermask Bottom")
		(17 "Dwgs.User" user "User.Drawings")
		(19 "Cmts.User" user "User.Comments")
		(21 "Eco1.User" user "User.Eco1")
		(23 "Eco2.User" user "User.Eco2")
		(25 "Edge.Cuts" user "Board Geometry/Outline")
		(27 "Margin" user)
		(31 "F.CrtYd" user "Package Geometry/Place Bound Top")
		(29 "B.CrtYd" user "Package Geometry/Place Bound Bottom")
		(35 "F.Fab" user "Ref Des/Assembly Top")
		(33 "B.Fab" user "Ref Des/Assembly Bottom")
	)
	(footprint ""
		(layer "F.Cu")
		(at 173.453552 -420.324534)
		(property "Reference" "Q102"
			(at -1.52908 -1.750568 0)
			(unlocked yes)
			(layer "F.SilkS")
			(effects
				(font
					(size 0.7874 0.5842)
					(thickness 0.1524)
				)
				(justify left)
			)
		)
		(property "Value" ""
			(at 0 0 0)
			(layer "F.Fab")
			(effects
				(font
					(size 1.27 1.27)
				)
			)
		)
		(duplicate_pad_numbers_are_jumpers no)
		(fp_line
			(start -1.332738 -1.100074)
			(end -0.4826 -1.100074)
			(stroke
				(width 0.1524)
				(type default)
			)
			(layer "F.SilkS")
		)
		(fp_line
			(start -1.332738 1.100074)
			(end -1.332738 -1.100074)
			(stroke
				(width 0.1524)
				(type default)
			)
			(layer "F.SilkS")
		)
		(fp_line
			(start -0.4826 -1.100074)
			(end 0 -0.541274)
			(stroke
				(width 0.1524)
				(type default)
			)
			(layer "F.SilkS")
		)
		(fp_line
			(start 0 -0.541274)
			(end 0.4826 -1.100074)
			(stroke
				(width 0.1524)
				(type default)
			)
			(layer "F.SilkS")
		)
		(fp_line
			(start 0.4826 -1.100074)
			(end 1.332738 -1.100074)
			(stroke
				(width 0.1524)
				(type default)
			)
			(layer "F.SilkS")
		)
		(fp_line
			(start 1.332738 -1.100074)
			(end 1.332738 1.100074)
			(stroke
				(width 0.1524)
				(type default)
			)
			(layer "F.SilkS")
		)
		(fp_line
			(start 1.332738 1.100074)
			(end -1.332738 1.100074)
			(stroke
				(width 0.1524)
				(type default)
			)
			(layer "F.SilkS")
		)
		(fp_poly
			(pts
				(xy -2.385568 -1.650746) (xy -1.683512 -1.299718) (xy -2.385568 -0.94869)
			)
			(stroke
				(width 0)
				(type default)
			)
			(fill yes)
			(layer "F.SilkS")
		)
		(fp_line
			(start -0.674878 -1.100074)
			(end 0.674878 -1.100074)
			(stroke
				(width 0.1)
				(type default)
			)
			(layer "F.Fab")
		)
		(fp_line
			(start -0.674878 1.100074)
			(end -0.674878 -1.100074)
			(stroke
				(width 0.1)
				(type default)
			)
			(layer "F.Fab")
		)
		(fp_line
			(start 0.674878 -1.100074)
			(end 0.674878 1.100074)
			(stroke
				(width 0.1)
				(type default)
			)
			(layer "F.Fab")
		)
		(fp_line
			(start 0.674878 1.100074)
			(end -0.674878 1.100074)
			(stroke
				(width 0.1)
				(type default)
			)
			(layer "F.Fab")
		)
		(fp_poly
			(pts
				(xy -2.2352 -0.298958) (xy -2.2352 -1.001014) (xy -1.533144 -0.649986)
			)
			(stroke
				(width 0)
				(type default)
			)
			(fill yes)
			(layer "F.Fab")
		)
		(pad "1" smd rect
			(at -0.94996 -0.649986 90)
			(size 0.4318 0.508)
			(layers "F.Cu" "F.Mask" "F.Paste")
			(net "GND")
		)
		(pad "2" smd rect
			(at -0.94996 0 90)
			(size 0.4318 0.508)
			(layers "F.Cu" "F.Mask" "F.Paste")
			(net "GPU_BASE_HMC_READY")
		)
		(pad "3" smd rect
			(at -0.94996 0.649986 90)
			(size 0.4318 0.508)
			(layers "F.Cu" "F.Mask" "F.Paste")
			(net "GPU_BASE_HMC_READY_ISO")
		)
		(pad "4" smd rect
			(at 0.94996 0.649986 90)
			(size 0.4318 0.508)
			(layers "F.Cu" "F.Mask" "F.Paste")
			(net "GND")
		)
		(pad "5" smd rect
			(at 0.94996 0 90)
			(size 0.4318 0.508)
			(layers "F.Cu" "F.Mask" "F.Paste")
			(net "GPU_BASE_HMC_READY_N")
		)
		(pad "6" smd rect
			(at 0.94996 -0.649986 90)
			(size 0.4318 0.508)
			(layers "F.Cu" "F.Mask" "F.Paste")
			(net "GPU_BASE_HMC_READY_N")
		)
	)
	(footprint ""
		(layer "F.Cu")
		(at 250.30303 -44.979082 -90)
		(property "Reference" "PR3960"
			(at 0 0 270)
			(layer "F.SilkS")
			(hide yes)
			(effects
				(font
					(size 1.27 1.27)
				)
			)
		)
		(property "Value" ""
			(at 0 0 270)
			(layer "F.Fab")
			(effects
				(font
					(size 1.27 1.27)
				)
			)
		)
		(duplicate_pad_numbers_are_jumpers no)
		(fp_line
			(start -0.7874 0.4064)
			(end -0.7874 -0.4064)
			(stroke
				(width 0.1524)
				(type default)
			)
			(layer "F.SilkS")
		)
		(fp_line
			(start 0.7874 0.4064)
			(end -0.7874 0.4064)
			(stroke
				(width 0.1524)
				(type default)
			)
			(layer "F.SilkS")
		)
		(fp_line
			(start -0.7874 -0.4064)
			(end 0.7874 -0.4064)
			(stroke
				(width 0.1524)
				(type default)
			)
			(layer "F.SilkS")
		)
		(fp_line
			(start 0.7874 -0.4064)
			(end 0.7874 0.4064)
			(stroke
				(width 0.1524)
				(type default)
			)
			(layer "F.SilkS")
		)
		(fp_line
			(start -0.67945 0.3048)
			(end -0.67945 -0.305054)
			(stroke
				(width 0.1)
				(type default)
			)
			(layer "F.Fab")
		)
		(fp_line
			(start -0.12065 0.3048)
			(end -0.67945 0.3048)
			(stroke
				(width 0.1)
				(type default)
			)
			(layer "F.Fab")
		)
		(fp_line
			(start 0.120396 0.3048)
			(end 0.120396 0.2794)
			(stroke
				(width 0.1)
				(type default)
			)
			(layer "F.Fab")
		)
		(fp_line
			(start 0.67945 0.3048)
			(end 0.120396 0.3048)
			(stroke
				(width 0.1)
				(type default)
			)
			(layer "F.Fab")
		)
		(fp_line
			(start -0.12065 0.2794)
			(end -0.12065 0.3048)
			(stroke
				(width 0.1)
				(type default)
			)
			(layer "F.Fab")
		)
		(fp_line
			(start 0.120396 0.2794)
			(end -0.12065 0.2794)
			(stroke
				(width 0.1)
				(type default)
			)
			(layer "F.Fab")
		)
		(fp_line
			(start -0.12065 -0.2794)
			(end 0.12065 -0.2794)
			(stroke
				(width 0.1)
				(type default)
			)
			(layer "F.Fab")
		)
		(fp_line
			(start 0.12065 -0.2794)
			(end 0.12065 -0.3048)
			(stroke
				(width 0.1)
				(type default)
			)
			(layer "F.Fab")
		)
		(fp_line
			(start 0.12065 -0.3048)
			(end 0.67945 -0.3048)
			(stroke
				(width 0.1)
				(type default)
			)
			(layer "F.Fab")
		)
		(fp_line
			(start 0.67945 -0.3048)
			(end 0.67945 0.3048)
			(stroke
				(width 0.1)
				(type default)
			)
			(layer "F.Fab")
		)
		(fp_line
			(start -0.67945 -0.305054)
			(end -0.12065 -0.305054)
			(stroke
				(width 0.1)
				(type default)
			)
			(layer "F.Fab")
		)
		(fp_line
			(start -0.12065 -0.305054)
			(end -0.12065 -0.2794)
			(stroke
				(width 0.1)
				(type default)
			)
			(layer "F.Fab")
		)
		(pad "1" smd circle
			(at -0.40005 0 270)
			(size 0 0)
			(layers "F.Cu" "F.Mask" "F.Paste")
			(net "P12V_AUX")
		)
		(pad "2" smd circle
			(at 0.40005 0 270)
			(size 0 0)
			(layers "F.Cu" "F.Mask" "F.Paste")
			(net "P12V_E1S_UV_0")
		)
	)
	(footprint ""
		(layer "F.Cu")
		(at 344.64879 -70.52056 90)
		(property "Reference" "C151"
			(at 0 0 90)
			(layer "F.SilkS")
			(hide yes)
			(effects
				(font
					(size 1.27 1.27)
				)
			)
		)
		(property "Value" ""
			(at 0 0 90)
			(layer "F.Fab")
			(effects
				(font
					(size 1.27 1.27)
				)
			)
		)
		(duplicate_pad_numbers_are_jumpers no)
		(fp_line
			(start 0.299974 -0.150114)
			(end 0.299974 0.150114)
			(stroke
				(width 0.1)
				(type default)
			)
			(layer "F.Fab")
		)
		(fp_line
			(start -0.299974 -0.150114)
			(end 0.299974 -0.150114)
			(stroke
				(width 0.1)
				(type default)
			)
			(layer "F.Fab")
		)
		(fp_line
			(start 0.299974 0.150114)
			(end -0.299974 0.150114)
			(stroke
				(width 0.1)
				(type default)
			)
			(layer "F.Fab")
		)
		(fp_line
			(start -0.299974 0.150114)
			(end -0.299974 -0.150114)
			(stroke
				(width 0.1)
				(type default)
			)
			(layer "F.Fab")
		)
		(pad "1" smd rect
			(at -0.2667 0 90)
			(size 0.3048 0.381)
			(layers "F.Cu" "F.Mask" "F.Paste")
			(net "DMI_CPU0_PCH_TX_C_DN<1>")
		)
		(pad "2" smd rect
			(at 0.2667 0 90)
			(size 0.3048 0.381)
			(layers "F.Cu" "F.Mask" "F.Paste")
			(net "DMI_CPU0_PCH_TX_DN<1>")
		)
	)
	(footprint ""
		(layer "F.Cu")
		(at 22.92223 -427.500034)
		(property "Reference" "R2738"
			(at 0 0 0)
			(layer "F.SilkS")
			(hide yes)
			(effects
				(font
					(size 1.27 1.27)
				)
			)
		)
		(property "Value" ""
			(at 0 0 0)
			(layer "F.Fab")
			(effects
				(font
					(size 1.27 1.27)
				)
			)
		)
		(duplicate_pad_numbers_are_jumpers no)
		(fp_line
			(start -0.7874 -0.4064)
			(end 0.7874 -0.4064)
			(stroke
				(width 0.1524)
				(type default)
			)
			(layer "F.SilkS")
		)
		(fp_line
			(start -0.7874 0.4064)
			(end -0.7874 -0.4064)
			(stroke
				(width 0.1524)
				(type default)
			)
			(layer "F.SilkS")
		)
		(fp_line
			(start 0.7874 -0.4064)
			(end 0.7874 0.4064)
			(stroke
				(width 0.1524)
				(type default)
			)
			(layer "F.SilkS")
		)
		(fp_line
			(start 0.7874 0.4064)
			(end -0.7874 0.4064)
			(stroke
				(width 0.1524)
				(type default)
			)
			(layer "F.SilkS")
		)
		(fp_line
			(start -0.67945 -0.305054)
			(end -0.12065 -0.305054)
			(stroke
				(width 0.1)
				(type default)
			)
			(layer "F.Fab")
		)
		(fp_line
			(start -0.67945 0.3048)
			(end -0.67945 -0.305054)
			(stroke
				(width 0.1)
				(type default)
			)
			(layer "F.Fab")
		)
		(fp_line
			(start -0.12065 -0.305054)
			(end -0.12065 -0.2794)
			(stroke
				(width 0.1)
				(type default)
			)
			(layer "F.Fab")
		)
		(fp_line
			(start -0.12065 -0.2794)
			(end 0.12065 -0.2794)
			(stroke
				(width 0.1)
				(type default)
			)
			(layer "F.Fab")
		)
		(fp_line
			(start -0.12065 0.2794)
			(end -0.12065 0.3048)
			(stroke
				(width 0.1)
				(type default)
			)
			(layer "F.Fab")
		)
		(fp_line
			(start -0.12065 0.3048)
			(end -0.67945 0.3048)
			(stroke
				(width 0.1)
				(type default)
			)
			(layer "F.Fab")
		)
		(fp_line
			(start 0.120396 0.2794)
			(end -0.12065 0.2794)
			(stroke
				(width 0.1)
				(type default)
			)
			(layer "F.Fab")
		)
		(fp_line
			(start 0.120396 0.3048)
			(end 0.120396 0.2794)
			(stroke
				(width 0.1)
				(type default)
			)
			(layer "F.Fab")
		)
		(fp_line
			(start 0.12065 -0.3048)
			(end 0.67945 -0.3048)
			(stroke
				(width 0.1)
				(type default)
			)
			(layer "F.Fab")
		)
		(fp_line
			(start 0.12065 -0.2794)
			(end 0.12065 -0.3048)
			(stroke
				(width 0.1)
				(type default)
			)
			(layer "F.Fab")
		)
		(fp_line
			(start 0.67945 -0.3048)
			(end 0.67945 0.3048)
			(stroke
				(width 0.1)
				(type default)
			)
			(layer "F.Fab")
		)
		(fp_line
			(start 0.67945 0.3048)
			(end 0.120396 0.3048)
			(stroke
				(width 0.1)
				(type default)
			)
			(layer "F.Fab")
		)
		(pad "1" smd circle
			(at -0.40005 0)
			(size 0 0)
			(layers "F.Cu" "F.Mask" "F.Paste")
			(net "RST_PERST_SWB_N")
		)
		(pad "2" smd circle
			(at 0.40005 0)
			(size 0 0)
			(layers "F.Cu" "F.Mask" "F.Paste")
			(net "RST_PERST_SWB_R_N")
		)
	)
	(footprint ""
		(layer "F.Cu")
		(at 435.91226 -92.700348)
		(property "Reference" "C2027"
			(at 0 0 0)
			(layer "F.SilkS")
			(hide yes)
			(effects
				(font
					(size 1.27 1.27)
				)
			)
		)
		(property "Value" ""
			(at 0 0 0)
			(layer "F.Fab")
			(effects
				(font
					(size 1.27 1.27)
				)
			)
		)
		(duplicate_pad_numbers_are_jumpers no)
		(fp_line
			(start -0.7874 -0.4064)
			(end 0.7874 -0.4064)
			(stroke
				(width 0.1524)
				(type default)
			)
			(layer "F.SilkS")
		)
		(fp_line
			(start -0.7874 0.4064)
			(end -0.7874 -0.4064)
			(stroke
				(width 0.1524)
				(type default)
			)
			(layer "F.SilkS")
		)
		(fp_line
			(start 0.7874 -0.4064)
			(end 0.7874 0.4064)
			(stroke
				(width 0.1524)
				(type default)
			)
			(layer "F.SilkS")
		)
		(fp_line
			(start 0.7874 0.4064)
			(end -0.7874 0.4064)
			(stroke
				(width 0.1524)
				(type default)
			)
			(layer "F.SilkS")
		)
		(fp_line
			(start -0.67945 -0.305054)
			(end -0.12065 -0.305054)
			(stroke
				(width 0.1)
				(type default)
			)
			(layer "F.Fab")
		)
		(fp_line
			(start -0.67945 0.3048)
			(end -0.67945 -0.305054)
			(stroke
				(width 0.1)
				(type default)
			)
			(layer "F.Fab")
		)
		(fp_line
			(start -0.12065 -0.305054)
			(end -0.12065 -0.2794)
			(stroke
				(width 0.1)
				(type default)
			)
			(layer "F.Fab")
		)
		(fp_line
			(start -0.12065 -0.2794)
			(end 0.12065 -0.2794)
			(stroke
				(width 0.1)
				(type default)
			)
			(layer "F.Fab")
		)
		(fp_line
			(start -0.12065 0.2794)
			(end -0.12065 0.3048)
			(stroke
				(width 0.1)
				(type default)
			)
			(layer "F.Fab")
		)
		(fp_line
			(start -0.12065 0.3048)
			(end -0.67945 0.3048)
			(stroke
				(width 0.1)
				(type default)
			)
			(layer "F.Fab")
		)
		(fp_line
			(start 0.120396 0.2794)
			(end -0.12065 0.2794)
			(stroke
				(width 0.1)
				(type default)
			)
			(layer "F.Fab")
		)
		(fp_line
			(start 0.120396 0.3048)
			(end 0.120396 0.2794)
			(stroke
				(width 0.1)
				(type default)
			)
			(layer "F.Fab")
		)
		(fp_line
			(start 0.12065 -0.3048)
			(end 0.67945 -0.3048)
			(stroke
				(width 0.1)
				(type default)
			)
			(layer "F.Fab")
		)
		(fp_line
			(start 0.12065 -0.2794)
			(end 0.12065 -0.3048)
			(stroke
				(width 0.1)
				(type default)
			)
			(layer "F.Fab")
		)
		(fp_line
			(start 0.67945 -0.3048)
			(end 0.67945 0.3048)
			(stroke
				(width 0.1)
				(type default)
			)
			(layer "F.Fab")
		)
		(fp_line
			(start 0.67945 0.3048)
			(end 0.120396 0.3048)
			(stroke
				(width 0.1)
				(type default)
			)
			(layer "F.Fab")
		)
		(pad "1" smd circle
			(at -0.40005 0)
			(size 0 0)
			(layers "F.Cu" "F.Mask" "F.Paste")
			(net "VSENSE_P3V3_INA230_1_INP")
		)
		(pad "2" smd circle
			(at 0.40005 0)
			(size 0 0)
			(layers "F.Cu" "F.Mask" "F.Paste")
			(net "VSENSE_P3V3_INA230_1_INN")
		)
	)
)
